(kicad_pcb
	(version 20241229)
	(generator "pcbnew")
	(generator_version "9.0")
	(general
		(thickness 1.599998)
		(legacy_teardrops no)
	)
	(paper "A4")
	(title_block
		(date "2023-02-12")
		(rev "1.1.5")
		(comment 9 "footprints 127-129 of 473")
	)
	(layers
		(0 "F.Cu" signal)
		(4 "In1.Cu" power "In1.GND")
		(6 "In2.Cu" signal)
		(8 "In3.Cu" power "In3.GND")
		(10 "In4.Cu" power "In4.VCC")
		(12 "In5.Cu" signal)
		(14 "In6.Cu" power "In6.VCC")
		(2 "B.Cu" signal)
		(9 "F.Adhes" user "F.Adhesive")
		(11 "B.Adhes" user "B.Adhesive")
		(13 "F.Paste" user)
		(15 "B.Paste" user)
		(5 "F.SilkS" user "F.Silkscreen")
		(7 "B.SilkS" user "B.Silkscreen")
		(1 "F.Mask" user)
		(3 "B.Mask" user)
		(17 "Dwgs.User" user "User.Drawings")
		(19 "Cmts.User" user "User.Comments")
		(21 "Eco1.User" user "User.Eco1")
		(23 "Eco2.User" user "User.Eco2")
		(25 "Edge.Cuts" user)
		(27 "Margin" user)
		(31 "F.CrtYd" user "F.Courtyard")
		(29 "B.CrtYd" user "B.Courtyard")
		(35 "F.Fab" user)
		(33 "B.Fab" user)
	)
	(footprint "antmicro-footprints:R_0402_1005Metric"
		(layer "F.Cu")
		(at 193.586328 104.474306 -90)
		(descr "Resistor SMD 0402")
		(tags "resistor SMD 0402")
		(property "Reference" "R73"
			(at 1.025694 -1.313672 270)
			(layer "F.SilkS")
			(effects
				(font
					(size 0.7 0.7)
					(thickness 0.15)
				)
				(justify left bottom)
			)
		)
		(property "Value" "R_1M8_0402"
			(at 0 1.4 270)
			(layer "F.Fab")
			(effects
				(font
					(size 0.7 0.7)
					(thickness 0.15)
				)
				(justify left bottom)
			)
		)
		(property "Description" "1M8 resistor in 0402 package with 1% tolerance"
			(at 0 0 270)
			(layer "F.Fab")
			(hide yes)
			(effects
				(font
					(size 1.27 1.27)
					(thickness 0.15)
				)
			)
		)
		(property "Author" "Antmicro"
			(at 89.112022 298.060634 0)
			(layer "F.Fab")
			(hide yes)
			(effects
				(font
					(size 1 1)
					(thickness 0.15)
				)
			)
		)
		(property "License" "Apache-2.0"
			(at 89.112022 298.060634 0)
			(layer "F.Fab")
			(hide yes)
			(effects
				(font
					(size 1 1)
					(thickness 0.15)
				)
			)
		)
		(property "MPN" "CR0402-FX-1804GLF"
			(at 89.112022 298.060634 0)
			(layer "F.Fab")
			(hide yes)
			(effects
				(font
					(size 1 1)
					(thickness 0.15)
				)
			)
		)
		(property "Manufacturer" "Bourns"
			(at 89.112022 298.060634 0)
			(layer "F.Fab")
			(hide yes)
			(effects
				(font
					(size 1 1)
					(thickness 0.15)
				)
			)
		)
		(property "Tolerance" "1%"
			(at 89.112022 298.060634 0)
			(layer "F.Fab")
			(hide yes)
			(effects
				(font
					(size 1 1)
					(thickness 0.15)
				)
			)
		)
		(property "Val" "1M8"
			(at 89.112022 298.060634 0)
			(layer "F.Fab")
			(hide yes)
			(effects
				(font
					(size 1 1)
					(thickness 0.15)
				)
			)
		)
		(sheetname "Ethernet")
		(sheetfile "ethernet.kicad_sch")
		(attr smd)
		(fp_rect
			(start -0.93 -0.47)
			(end 0.93 0.47)
			(stroke
				(width 0.05)
				(type solid)
			)
			(fill no)
			(layer "F.CrtYd")
		)
		(fp_rect
			(start -0.5 -0.25)
			(end 0.5 0.25)
			(stroke
				(width 0.15)
				(type solid)
			)
			(fill no)
			(layer "F.Fab")
		)
		(pad "1" smd roundrect
			(at -0.485 0 270)
			(size 0.59 0.64)
			(layers "F.Cu" "F.Mask" "F.Paste")
			(roundrect_rratio 0.25)
			(net 656 "ETH_XO")
			(pintype "passive")
		)
		(pad "2" smd roundrect
			(at 0.485 0 270)
			(size 0.59 0.64)
			(layers "F.Cu" "F.Mask" "F.Paste")
			(roundrect_rratio 0.25)
			(net 657 "ETH_XI")
			(pintype "passive")
		)
	)
	(footprint "antmicro-footprints:Spacer_Drill3.7mm_H5mm_9774050151R"
		(layer "F.Cu")
		(at 154.136328 49.747157)
		(descr "Spacer steel M2.5 h=5mm fi=5.1mm")
		(property "Reference" "SP1"
			(at 3.597672 0.290843 0)
			(layer "F.SilkS")
			(effects
				(font
					(size 0.7 0.7)
					(thickness 0.15)
				)
				(justify left bottom)
			)
		)
		(property "Value" "Spacer_H5.0mm_9774050151"
			(at 0 4 0)
			(layer "F.Fab")
			(effects
				(font
					(size 0.7 0.7)
					(thickness 0.15)
				)
				(justify left bottom)
			)
		)
		(property "Description" "Spacer, SMT, Non Stop, Steel, Swage Round, 5.1 mm x 5 mm, M2.5 Thread, WA-SMSI Series"
			(at 0 0 0)
			(layer "F.Fab")
			(hide yes)
			(effects
				(font
					(size 1.27 1.27)
					(thickness 0.15)
				)
			)
		)
		(property "Author" "Antmicro"
			(at 0 0 0)
			(layer "F.Fab")
			(hide yes)
			(effects
				(font
					(size 1 1)
					(thickness 0.15)
				)
			)
		)
		(property "License" "Apache-2.0"
			(at 0 0 0)
			(layer "F.Fab")
			(hide yes)
			(effects
				(font
					(size 1 1)
					(thickness 0.15)
				)
			)
		)
		(property "MPN" "9774050151R"
			(at 0 0 0)
			(layer "F.Fab")
			(hide yes)
			(effects
				(font
					(size 1 1)
					(thickness 0.15)
				)
			)
		)
		(property "Manufacturer" "Würth Elektronik"
			(at 0 0 0)
			(layer "F.Fab")
			(hide yes)
			(effects
				(font
					(size 1 1)
					(thickness 0.15)
				)
			)
		)
		(sheetname "SO-DIMM")
		(sheetfile "sodimm.kicad_sch")
		(attr smd)
		(fp_circle
			(center 0 0)
			(end 0.05 -3.05)
			(stroke
				(width 0.05)
				(type solid)
			)
			(fill no)
			(layer "F.CrtYd")
		)
		(pad "1" thru_hole circle
			(at 0 0)
			(size 6 6)
			(drill 3.7)
			(layers "*.Cu" "*.Mask" "F.Paste")
			(remove_unused_layers no)
			(net 203 "unconnected-(SP1-Pad1)")
			(pintype "passive+no_connect")
			(solder_paste_margin_ratio -0.05)
		)
	)
	(footprint "antmicro-footprints:SW_Slide_E-Switch_EG1218"
		(layer "F.Cu")
		(at 184.236828 125.647157 -90)
		(property "Reference" "S1"
			(at -3.747157 2.336828 0)
			(layer "F.SilkS")
			(effects
				(font
					(size 0.7 0.7)
					(thickness 0.15)
				)
				(justify left bottom)
			)
		)
		(property "Value" "SW_EG1218"
			(at 0 3.5 270)
			(layer "F.Fab")
			(effects
				(font
					(size 0.7 0.7)
					(thickness 0.15)
				)
				(justify left bottom)
			)
		)
		(property "Description" "E-Switch Slide Switches PC MNT 3 PIN SLIDE"
			(at 0 0 270)
			(layer "F.Fab")
			(hide yes)
			(effects
				(font
					(size 1.27 1.27)
					(thickness 0.15)
				)
			)
		)
		(property "Author" "Antmicro"
			(at 58.589671 309.883985 0)
			(layer "F.Fab")
			(hide yes)
			(effects
				(font
					(size 1 1)
					(thickness 0.15)
				)
			)
		)
		(property "License" "Apache-2.0"
			(at 58.589671 309.883985 0)
			(layer "F.Fab")
			(hide yes)
			(effects
				(font
					(size 1 1)
					(thickness 0.15)
				)
			)
		)
		(property "MPN" "EG1218"
			(at 58.589671 309.883985 0)
			(layer "F.Fab")
			(hide yes)
			(effects
				(font
					(size 1 1)
					(thickness 0.15)
				)
			)
		)
		(property "Manufacturer" "E-Switch"
			(at 58.589671 309.883985 0)
			(layer "F.Fab")
			(hide yes)
			(effects
				(font
					(size 1 1)
					(thickness 0.15)
				)
			)
		)
		(sheetname "Supply")
		(sheetfile "supply.kicad_sch")
		(attr through_hole)
		(fp_line
			(start -3.5 2.2)
			(end -3 2.2)
			(stroke
				(width 0.15)
				(type solid)
			)
			(layer "F.SilkS")
		)
		(fp_line
			(start -3.5 2.2)
			(end -3.5 1.7)
			(stroke
				(width 0.15)
				(type solid)
			)
			(layer "F.SilkS")
		)
		(fp_line
			(start 8.5 2.2)
			(end 7.999 2.2)
			(stroke
				(width 0.15)
				(type solid)
			)
			(layer "F.SilkS")
		)
		(fp_line
			(start 8.5 2.2)
			(end 8.5 1.7)
			(stroke
				(width 0.15)
				(type solid)
			)
			(layer "F.SilkS")
		)
		(fp_line
			(start -3.5 -2.2)
			(end -3.5 -1.7)
			(stroke
				(width 0.15)
				(type solid)
			)
			(layer "F.SilkS")
		)
		(fp_line
			(start -3.5 -2.2)
			(end -3 -2.2)
			(stroke
				(width 0.15)
				(type solid)
			)
			(layer "F.SilkS")
		)
		(fp_line
			(start 8.5 -2.2)
			(end 8.5 -1.7)
			(stroke
				(width 0.15)
				(type solid)
			)
			(layer "F.SilkS")
		)
		(fp_line
			(start 8.5 -2.2)
			(end 7.999 -2.2)
			(stroke
				(width 0.15)
				(type solid)
			)
			(layer "F.SilkS")
		)
		(fp_rect
			(start -3.6 -2.299)
			(end 8.6 2.3)
			(stroke
				(width 0.05)
				(type solid)
			)
			(fill no)
			(layer "F.CrtYd")
		)
		(fp_rect
			(start 8.3 -2)
			(end -3.3 2)
			(stroke
				(width 0.15)
				(type solid)
			)
			(fill no)
			(layer "F.Fab")
		)
		(pad "1" thru_hole rect
			(at 0 0 270)
			(size 1.9 1.9)
			(drill 0.9)
			(layers "*.Cu" "*.Mask")
			(remove_unused_layers no)
			(net 202 "unconnected-(S1-Pad1)")
			(pintype "passive+no_connect")
		)
		(pad "2" thru_hole circle
			(at 2.499 0 270)
			(size 1.9 1.9)
			(drill 0.9)
			(layers "*.Cu" "*.Mask")
			(remove_unused_layers no)
			(net 514 "/Supply/SYS_EN")
			(pintype "passive")
		)
		(pad "3" thru_hole circle
			(at 4.998 0 270)
			(size 1.9 1.9)
			(drill 0.9)
			(layers "*.Cu" "*.Mask")
			(remove_unused_layers no)
			(net 5 "GND")
			(pintype "passive")
		)
	)
)
